# S9S_MB_2U (Grand Teton) — schematic netlist excerpt (pin names and nets, part order shuffled) for the footprints in the layout excerpt that follows; sources: Cadence DE-HDL packaged netlist, KiCad conversion of 03242023_DA0F0TMBIJ0_F0T_Motherboard_J_brd_V01_OCP.brd

R3088  Q_RES  130 1% CHIP  pkg 0402LF  page 253 : A = LED_PWRGD_PVCCFA_EHV_FIVRA_CPU0 ; B = P3V3_AUX
R3730  Q_RES  2.2K 5% CHIP  pkg 0402LF  page 233 : A = P3V3_AUX ; B = SMB_LM75_2_3V3AUX_SDA

(kicad_pcb
	(version 20260206)
	(generator "pcbnew")
	(generator_version "10.0")
	(general
		(thickness 1.6)
		(legacy_teardrops no)
	)
	(paper "A4")
	(title_block
		(title "03242023_DA0F0TMBIJ0_F0T_Motherboard_J_brd_V01_OCP.brd")
		(comment 1 "Grand Teton / footprints 1500-1501 of 6105")
	)
	(layers
		(0 "F.Cu" signal "TOP")
		(4 "In1.Cu" signal "GND")
		(6 "In2.Cu" signal "IN1")
		(8 "In3.Cu" signal "GND1")
		(10 "In4.Cu" signal "IN2")
		(12 "In5.Cu" signal "GND2")
		(14 "In6.Cu" signal "IN3")
		(16 "In7.Cu" signal "GND3")
		(18 "In8.Cu" signal "VCC")
		(20 "In9.Cu" signal "VCC1")
		(22 "In10.Cu" signal "GND4")
		(24 "In11.Cu" signal "IN4")
		(26 "In12.Cu" signal "GND5")
		(28 "In13.Cu" signal "IN5")
		(30 "In14.Cu" signal "GND6")
		(32 "In15.Cu" signal "IN6")
		(34 "In16.Cu" signal "GND7")
		(2 "B.Cu" signal "BOTTOM")
		(9 "F.Adhes" user "F.Adhesive")
		(11 "B.Adhes" user "B.Adhesive")
		(13 "F.Paste" user "Package Geometry/Pastemask Top")
		(15 "B.Paste" user "Package Geometry/Pastemask Bottom")
		(5 "F.SilkS" user "Ref Des/Silkscreen Top")
		(7 "B.SilkS" user "Ref Des/Silkscreen Bottom")
		(1 "F.Mask" user "Board Geometry/Soldermask Top")
		(3 "B.Mask" user "Board Geometry/Soldermask Bottom")
		(17 "Dwgs.User" user "User.Drawings")
		(19 "Cmts.User" user "User.Comments")
		(21 "Eco1.User" user "User.Eco1")
		(23 "Eco2.User" user "User.Eco2")
		(25 "Edge.Cuts" user "Board Geometry/Outline")
		(27 "Margin" user)
		(31 "F.CrtYd" user "Package Geometry/Place Bound Top")
		(29 "B.CrtYd" user "Package Geometry/Place Bound Bottom")
		(35 "F.Fab" user "Ref Des/Assembly Top")
		(33 "B.Fab" user "Ref Des/Assembly Bottom")
	)
	(footprint ""
		(layer "F.Cu")
		(at 73.475596 -74.901552 -90)
		(property "Reference" "R3088"
			(at 0 0 270)
			(layer "F.SilkS")
			(hide yes)
			(effects
				(font
					(size 1.27 1.27)
				)
			)
		)
		(property "Value" ""
			(at 0 0 270)
			(layer "F.Fab")
			(effects
				(font
					(size 1.27 1.27)
				)
			)
		)
		(duplicate_pad_numbers_are_jumpers no)
		(fp_line
			(start -0.7874 0.4064)
			(end -0.7874 -0.4064)
			(stroke
				(width 0.1524)
				(type default)
			)
			(layer "F.SilkS")
		)
		(fp_line
			(start 0.7874 0.4064)
			(end -0.7874 0.4064)
			(stroke
				(width 0.1524)
				(type default)
			)
			(layer "F.SilkS")
		)
		(fp_line
			(start -0.7874 -0.4064)
			(end 0.7874 -0.4064)
			(stroke
				(width 0.1524)
				(type default)
			)
			(layer "F.SilkS")
		)
		(fp_line
			(start 0.7874 -0.4064)
			(end 0.7874 0.4064)
			(stroke
				(width 0.1524)
				(type default)
			)
			(layer "F.SilkS")
		)
		(fp_line
			(start -0.67945 0.3048)
			(end -0.67945 -0.305054)
			(stroke
				(width 0.1)
				(type default)
			)
			(layer "F.Fab")
		)
		(fp_line
			(start -0.12065 0.3048)
			(end -0.67945 0.3048)
			(stroke
				(width 0.1)
				(type default)
			)
			(layer "F.Fab")
		)
		(fp_line
			(start 0.120396 0.3048)
			(end 0.120396 0.2794)
			(stroke
				(width 0.1)
				(type default)
			)
			(layer "F.Fab")
		)
		(fp_line
			(start 0.67945 0.3048)
			(end 0.120396 0.3048)
			(stroke
				(width 0.1)
				(type default)
			)
			(layer "F.Fab")
		)
		(fp_line
			(start -0.12065 0.2794)
			(end -0.12065 0.3048)
			(stroke
				(width 0.1)
				(type default)
			)
			(layer "F.Fab")
		)
		(fp_line
			(start 0.120396 0.2794)
			(end -0.12065 0.2794)
			(stroke
				(width 0.1)
				(type default)
			)
			(layer "F.Fab")
		)
		(fp_line
			(start -0.12065 -0.2794)
			(end 0.12065 -0.2794)
			(stroke
				(width 0.1)
				(type default)
			)
			(layer "F.Fab")
		)
		(fp_line
			(start 0.12065 -0.2794)
			(end 0.12065 -0.3048)
			(stroke
				(width 0.1)
				(type default)
			)
			(layer "F.Fab")
		)
		(fp_line
			(start 0.12065 -0.3048)
			(end 0.67945 -0.3048)
			(stroke
				(width 0.1)
				(type default)
			)
			(layer "F.Fab")
		)
		(fp_line
			(start 0.67945 -0.3048)
			(end 0.67945 0.3048)
			(stroke
				(width 0.1)
				(type default)
			)
			(layer "F.Fab")
		)
		(fp_line
			(start -0.67945 -0.305054)
			(end -0.12065 -0.305054)
			(stroke
				(width 0.1)
				(type default)
			)
			(layer "F.Fab")
		)
		(fp_line
			(start -0.12065 -0.305054)
			(end -0.12065 -0.2794)
			(stroke
				(width 0.1)
				(type default)
			)
			(layer "F.Fab")
		)
		(pad "1" smd circle
			(at -0.40005 0 270)
			(size 0 0)
			(layers "F.Cu" "F.Mask" "F.Paste")
			(net "LED_PWRGD_PVCCFA_EHV_FIVRA_CPU0")
		)
		(pad "2" smd circle
			(at 0.40005 0 270)
			(size 0 0)
			(layers "F.Cu" "F.Mask" "F.Paste")
			(net "P3V3_AUX")
		)
	)
	(footprint ""
		(layer "F.Cu")
		(at 51.593496 -106.74477)
		(property "Reference" "R3730"
			(at 0 0 0)
			(layer "F.SilkS")
			(hide yes)
			(effects
				(font
					(size 1.27 1.27)
				)
			)
		)
		(property "Value" ""
			(at 0 0 0)
			(layer "F.Fab")
			(effects
				(font
					(size 1.27 1.27)
				)
			)
		)
		(duplicate_pad_numbers_are_jumpers no)
		(fp_line
			(start -0.7874 -0.4064)
			(end 0.7874 -0.4064)
			(stroke
				(width 0.1524)
				(type default)
			)
			(layer "F.SilkS")
		)
		(fp_line
			(start -0.7874 0.4064)
			(end -0.7874 -0.4064)
			(stroke
				(width 0.1524)
				(type default)
			)
			(layer "F.SilkS")
		)
		(fp_line
			(start 0.7874 -0.4064)
			(end 0.7874 0.4064)
			(stroke
				(width 0.1524)
				(type default)
			)
			(layer "F.SilkS")
		)
		(fp_line
			(start 0.7874 0.4064)
			(end -0.7874 0.4064)
			(stroke
				(width 0.1524)
				(type default)
			)
			(layer "F.SilkS")
		)
		(fp_line
			(start -0.67945 -0.305054)
			(end -0.12065 -0.305054)
			(stroke
				(width 0.1)
				(type default)
			)
			(layer "F.Fab")
		)
		(fp_line
			(start -0.67945 0.3048)
			(end -0.67945 -0.305054)
			(stroke
				(width 0.1)
				(type default)
			)
			(layer "F.Fab")
		)
		(fp_line
			(start -0.12065 -0.305054)
			(end -0.12065 -0.2794)
			(stroke
				(width 0.1)
				(type default)
			)
			(layer "F.Fab")
		)
		(fp_line
			(start -0.12065 -0.2794)
			(end 0.12065 -0.2794)
			(stroke
				(width 0.1)
				(type default)
			)
			(layer "F.Fab")
		)
		(fp_line
			(start -0.12065 0.2794)
			(end -0.12065 0.3048)
			(stroke
				(width 0.1)
				(type default)
			)
			(layer "F.Fab")
		)
		(fp_line
			(start -0.12065 0.3048)
			(end -0.67945 0.3048)
			(stroke
				(width 0.1)
				(type default)
			)
			(layer "F.Fab")
		)
		(fp_line
			(start 0.120396 0.2794)
			(end -0.12065 0.2794)
			(stroke
				(width 0.1)
				(type default)
			)
			(layer "F.Fab")
		)
		(fp_line
			(start 0.120396 0.3048)
			(end 0.120396 0.2794)
			(stroke
				(width 0.1)
				(type default)
			)
			(layer "F.Fab")
		)
		(fp_line
			(start 0.12065 -0.3048)
			(end 0.67945 -0.3048)
			(stroke
				(width 0.1)
				(type default)
			)
			(layer "F.Fab")
		)
		(fp_line
			(start 0.12065 -0.2794)
			(end 0.12065 -0.3048)
			(stroke
				(width 0.1)
				(type default)
			)
			(layer "F.Fab")
		)
		(fp_line
			(start 0.67945 -0.3048)
			(end 0.67945 0.3048)
			(stroke
				(width 0.1)
				(type default)
			)
			(layer "F.Fab")
		)
		(fp_line
			(start 0.67945 0.3048)
			(end 0.120396 0.3048)
			(stroke
				(width 0.1)
				(type default)
			)
			(layer "F.Fab")
		)
		(pad "1" smd circle
			(at -0.40005 0)
			(size 0 0)
			(layers "F.Cu" "F.Mask" "F.Paste")
			(net "P3V3_AUX")
		)
		(pad "2" smd circle
			(at 0.40005 0)
			(size 0 0)
			(layers "F.Cu" "F.Mask" "F.Paste")
			(net "SMB_LM75_2_3V3AUX_SDA")
		)
	)
)
